# TIMECARD (Time Appliance Project (Time Card)) — schematic netlist excerpt (pin names and nets, part order shuffled) for the footprints in the layout excerpt that follows; sources: Cadence DE-HDL packaged netlist, KiCad conversion of R4006-B0001-02_R01.brd

U32  PCA9508DP_TSSOP8  pkg SOP8_118_P0256_V2  page 19
  VCC_A  = XP1R8V_ICP10100
  SCLA  = BF_ICP10100_I2C_SCL
  SDAA  = BF_ICP10100_I2C_SDA
  GND  = SG
  EN  = UNNAMED_8_PCA9508DPTSSOP8_I51_E
  SDAB  = ICP10100_I2C_SDA
  SCLB  = ICP10100_I2C_SCL
  VCC_B  = XP3R3V

(kicad_pcb
	(version 20260206)
	(generator "pcbnew")
	(generator_version "10.0")
	(general
		(thickness 1.6)
		(legacy_teardrops no)
	)
	(paper "A4")
	(title_block
		(title "timecard-production-celestica-r4006 — R4006-B0001-02_R01.brd")
		(comment 1 "Time Appliance Project (Time Card) / footprints 17-17 of 1113")
	)
	(layers
		(0 "F.Cu" signal "TOP")
		(4 "In1.Cu" signal "L02_GND1")
		(6 "In2.Cu" signal "L03_SIG1")
		(8 "In3.Cu" signal "L04_GND2")
		(10 "In4.Cu" signal "L05_VCC1")
		(12 "In5.Cu" signal "L06_VCC2")
		(14 "In6.Cu" signal "L07_GND3")
		(16 "In7.Cu" signal "L08_SIG2")
		(18 "In8.Cu" signal "L09_GND4")
		(2 "B.Cu" signal "BOTTOM")
		(9 "F.Adhes" user "F.Adhesive")
		(11 "B.Adhes" user "B.Adhesive")
		(13 "F.Paste" user "Package Geometry/Pastemask Top")
		(15 "B.Paste" user "Package Geometry/Pastemask Bottom")
		(5 "F.SilkS" user "Ref Des/Silkscreen Top")
		(7 "B.SilkS" user "Ref Des/Silkscreen Bottom")
		(1 "F.Mask" user "Board Geometry/Soldermask Top")
		(3 "B.Mask" user "Board Geometry/Soldermask Bottom")
		(17 "Dwgs.User" user "User.Drawings")
		(19 "Cmts.User" user "User.Comments")
		(21 "Eco1.User" user "User.Eco1")
		(23 "Eco2.User" user "User.Eco2")
		(25 "Edge.Cuts" user "Board Geometry/Outline")
		(27 "Margin" user)
		(31 "F.CrtYd" user "Package Geometry/Place Bound Top")
		(29 "B.CrtYd" user "Package Geometry/Place Bound Bottom")
		(35 "F.Fab" user "Ref Des/Assembly Top")
		(33 "B.Fab" user "Ref Des/Assembly Bottom")
	)
	(footprint ""
		(layer "F.Cu")
		(at 20.8534 -59.3598 90)
		(property "Reference" "U32"
			(at 0.0762 2.68097 90)
			(unlocked yes)
			(layer "F.SilkS")
			(effects
				(font
					(size 0.7874 0.5842)
					(thickness 0.1524)
				)
			)
		)
		(property "Value" ""
			(at 0 0 90)
			(layer "F.Fab")
			(effects
				(font
					(size 1.27 1.27)
				)
			)
		)
		(property "Device Type" "PCA9508DP_TSSOP8-G223-10278-01"
			(at -0.03175 2.55651 90)
			(unlocked yes)
			(layer "F.Fab")
			(hide yes)
			(effects
				(font
					(size 0.7874 0.5842)
					(thickness 0.1524)
				)
			)
		)
		(property "User Part Number" "PARTNUM*"
			(at -0.037592 3.488182 90)
			(unlocked yes)
			(layer "Cmts.User")
			(hide yes)
			(effects
				(font
					(size 0.7874 0.5842)
					(thickness 0.1524)
				)
			)
		)
		(duplicate_pad_numbers_are_jumpers no)
		(fp_line
			(start 1.778 -1.778)
			(end -1.778 -1.778)
			(stroke
				(width 0.1)
				(type default)
			)
			(layer "F.SilkS")
		)
		(fp_line
			(start -1.778 -1.778)
			(end -1.778 -1.45796)
			(stroke
				(width 0.1)
				(type default)
			)
			(layer "F.SilkS")
		)
		(fp_line
			(start 3.3147 -1.45796)
			(end 1.778 -1.45796)
			(stroke
				(width 0.1)
				(type default)
			)
			(layer "F.SilkS")
		)
		(fp_line
			(start 1.778 -1.45796)
			(end 1.778 -1.778)
			(stroke
				(width 0.1)
				(type default)
			)
			(layer "F.SilkS")
		)
		(fp_line
			(start -1.778 -1.45796)
			(end -3.3147 -1.45796)
			(stroke
				(width 0.1)
				(type default)
			)
			(layer "F.SilkS")
		)
		(fp_line
			(start -3.3147 -1.45796)
			(end -3.3147 1.45796)
			(stroke
				(width 0.1)
				(type default)
			)
			(layer "F.SilkS")
		)
		(fp_line
			(start 3.3147 1.45796)
			(end 3.3147 -1.45796)
			(stroke
				(width 0.1)
				(type default)
			)
			(layer "F.SilkS")
		)
		(fp_line
			(start 1.778 1.45796)
			(end 3.3147 1.45796)
			(stroke
				(width 0.1)
				(type default)
			)
			(layer "F.SilkS")
		)
		(fp_line
			(start -1.778 1.45796)
			(end -1.778 1.778)
			(stroke
				(width 0.1)
				(type default)
			)
			(layer "F.SilkS")
		)
		(fp_line
			(start -3.3147 1.45796)
			(end -1.778 1.45796)
			(stroke
				(width 0.1)
				(type default)
			)
			(layer "F.SilkS")
		)
		(fp_line
			(start 1.778 1.778)
			(end 1.778 1.45796)
			(stroke
				(width 0.1)
				(type default)
			)
			(layer "F.SilkS")
		)
		(fp_line
			(start -1.778 1.778)
			(end 1.778 1.778)
			(stroke
				(width 0.1)
				(type default)
			)
			(layer "F.SilkS")
		)
		(fp_poly
			(pts
				(arc
					(start -3.3528 -1.6764)
					(mid -3.3528 -2.4384)
					(end -3.3528 -1.6764)
				)
			)
			(stroke
				(width 0)
				(type default)
			)
			(fill yes)
			(layer "F.SilkS")
		)
		(fp_poly
			(pts
				(xy -3.5687 -2.032) (xy -3.5687 2.032) (xy 3.5687 2.032) (xy 3.5687 -2.032)
			)
			(stroke
				(width 0)
				(type default)
			)
			(fill no)
			(layer "F.CrtYd")
		)
		(fp_line
			(start 1.524 -1.524)
			(end 1.524 1.524)
			(stroke
				(width 0.1)
				(type default)
			)
			(layer "F.Fab")
		)
		(fp_line
			(start -1.524 -1.524)
			(end 1.524 -1.524)
			(stroke
				(width 0.1)
				(type default)
			)
			(layer "F.Fab")
		)
		(fp_line
			(start 1.524 1.524)
			(end -1.524 1.524)
			(stroke
				(width 0.1)
				(type default)
			)
			(layer "F.Fab")
		)
		(fp_line
			(start -1.524 1.524)
			(end -1.524 -1.524)
			(stroke
				(width 0.1)
				(type default)
			)
			(layer "F.Fab")
		)
		(fp_poly
			(pts
				(arc
					(start -0.9906 -0.5588)
					(mid -0.9906 -1.3208)
					(end -0.9906 -0.5588)
				)
			)
			(stroke
				(width 0)
				(type default)
			)
			(fill yes)
			(layer "F.Fab")
		)
		(fp_text user "8"
			(at 3.72745 -2.0574 0)
			(unlocked yes)
			(layer "F.SilkS")
			(effects
				(font
					(size 0.635 0.4064)
					(thickness 0.1524)
				)
			)
		)
		(fp_text user "4"
			(at -2.95275 2.1336 0)
			(unlocked yes)
			(layer "F.SilkS")
			(effects
				(font
					(size 0.635 0.4064)
					(thickness 0.1524)
				)
			)
		)
		(fp_text user "5"
			(at 2.96545 2.2606 0)
			(unlocked yes)
			(layer "F.SilkS")
			(effects
				(font
					(size 0.635 0.4064)
					(thickness 0.1524)
				)
			)
		)
		(fp_text user "8"
			(at 2.32283 -1.5494 0)
			(unlocked yes)
			(layer "F.Fab")
			(effects
				(font
					(size 0.7874 0.5842)
					(thickness 0.1524)
				)
			)
		)
		(fp_text user "4"
			(at -2.75717 1.4986 0)
			(unlocked yes)
			(layer "F.Fab")
			(effects
				(font
					(size 0.7874 0.5842)
					(thickness 0.1524)
				)
			)
		)
		(fp_text user "5"
			(at 2.32283 1.6256 0)
			(unlocked yes)
			(layer "F.Fab")
			(effects
				(font
					(size 0.7874 0.5842)
					(thickness 0.1524)
				)
			)
		)
		(pad "1" smd rect
			(at -2.2987 -0.97536 180)
			(size 0.4572 1.524)
			(layers "F.Cu" "F.Mask" "F.Paste")
			(net "XP1R8V_ICP10100")
		)
		(pad "2" smd rect
			(at -2.2987 -0.32512 180)
			(size 0.4572 1.524)
			(layers "F.Cu" "F.Mask" "F.Paste")
			(net "BF_ICP10100_I2C_SCL")
		)
		(pad "3" smd rect
			(at -2.2987 0.32512 180)
			(size 0.4572 1.524)
			(layers "F.Cu" "F.Mask" "F.Paste")
			(net "BF_ICP10100_I2C_SDA")
		)
		(pad "4" smd rect
			(at -2.2987 0.97536 180)
			(size 0.4572 1.524)
			(layers "F.Cu" "F.Mask" "F.Paste")
			(net "SG")
		)
		(pad "5" smd rect
			(at 2.2987 0.97536 180)
			(size 0.4572 1.524)
			(layers "F.Cu" "F.Mask" "F.Paste")
			(net "UNNAMED_8_PCA9508DPTSSOP8_I51_E")
		)
		(pad "6" smd rect
			(at 2.2987 0.32512 180)
			(size 0.4572 1.524)
			(layers "F.Cu" "F.Mask" "F.Paste")
			(net "ICP10100_I2C_SDA")
		)
		(pad "7" smd rect
			(at 2.2987 -0.32512 180)
			(size 0.4572 1.524)
			(layers "F.Cu" "F.Mask" "F.Paste")
			(net "ICP10100_I2C_SCL")
		)
		(pad "8" smd rect
			(at 2.2987 -0.97536 180)
			(size 0.4572 1.524)
			(layers "F.Cu" "F.Mask" "F.Paste")
			(net "XP3R3V")
		)
	)
)
